# SCM (Grand Teton) — schematic netlist excerpt (pin names and nets, part order shuffled) for the footprints in the layout excerpt that follows; sources: Cadence DE-HDL packaged netlist, KiCad conversion of 12092022_DA0F0TMDCD0_F0T_Management_Board_D_brd_V3_OCP.brd

R852  Q_RES  68.1 1% CHIP  pkg 0402LF  page 44 : A = FM_BMC_MUX_CS_SPI_SEL_0 ; B = FM_BMC_BIOS_MUX_CS_SPI_R_SEL_0
R819  Q_RES  100K 1% EMPTY  pkg 0402LF  page 12 : A = SMB_BMC_MM14_R_SCL ; B = GND

(kicad_pcb
	(version 20260206)
	(generator "pcbnew")
	(generator_version "10.0")
	(general
		(thickness 1.6)
		(legacy_teardrops no)
	)
	(paper "A4")
	(title_block
		(title "12092022_DA0F0TMDCD0_F0T_Management_Board_D_brd_V3_OCP.brd")
		(comment 1 "Grand Teton / footprints 990-991 of 1440")
	)
	(layers
		(0 "F.Cu" signal "TOP")
		(4 "In1.Cu" signal "GND")
		(6 "In2.Cu" signal "IN1")
		(8 "In3.Cu" signal "GND1")
		(10 "In4.Cu" signal "IN2")
		(12 "In5.Cu" signal "VCC")
		(14 "In6.Cu" signal "VCC1")
		(16 "In7.Cu" signal "IN3")
		(18 "In8.Cu" signal "GND2")
		(20 "In9.Cu" signal "IN4")
		(22 "In10.Cu" signal "GND3")
		(2 "B.Cu" signal "BOTTOM")
		(9 "F.Adhes" user "F.Adhesive")
		(11 "B.Adhes" user "B.Adhesive")
		(13 "F.Paste" user "Package Geometry/Pastemask Top")
		(15 "B.Paste" user "Package Geometry/Pastemask Bottom")
		(5 "F.SilkS" user "Ref Des/Silkscreen Top")
		(7 "B.SilkS" user "Ref Des/Silkscreen Bottom")
		(1 "F.Mask" user "Board Geometry/Soldermask Top")
		(3 "B.Mask" user "Board Geometry/Soldermask Bottom")
		(17 "Dwgs.User" user "User.Drawings")
		(19 "Cmts.User" user "User.Comments")
		(21 "Eco1.User" user "User.Eco1")
		(23 "Eco2.User" user "User.Eco2")
		(25 "Edge.Cuts" user "Board Geometry/Outline")
		(27 "Margin" user)
		(31 "F.CrtYd" user "Package Geometry/Place Bound Top")
		(29 "B.CrtYd" user "Package Geometry/Place Bound Bottom")
		(35 "F.Fab" user "Ref Des/Assembly Top")
		(33 "B.Fab" user "Ref Des/Assembly Bottom")
	)
	(footprint ""
		(layer "B.Cu")
		(at 41.966134 -48.44415)
		(property "Reference" "R819"
			(at 0 0 0)
			(layer "B.SilkS")
			(hide yes)
			(effects
				(font
					(size 1.27 1.27)
				)
				(justify mirror)
			)
		)
		(property "Value" ""
			(at 0 0 0)
			(layer "B.Fab")
			(effects
				(font
					(size 1.27 1.27)
				)
				(justify mirror)
			)
		)
		(duplicate_pad_numbers_are_jumpers no)
		(fp_line
			(start -0.7874 -0.4064)
			(end -0.7874 0.4064)
			(stroke
				(width 0.1524)
				(type default)
			)
			(layer "B.SilkS")
		)
		(fp_line
			(start -0.7874 0.4064)
			(end 0.7874 0.4064)
			(stroke
				(width 0.1524)
				(type default)
			)
			(layer "B.SilkS")
		)
		(fp_line
			(start 0.7874 -0.4064)
			(end -0.7874 -0.4064)
			(stroke
				(width 0.1524)
				(type default)
			)
			(layer "B.SilkS")
		)
		(fp_line
			(start 0.7874 0.4064)
			(end 0.7874 -0.4064)
			(stroke
				(width 0.1524)
				(type default)
			)
			(layer "B.SilkS")
		)
		(fp_line
			(start -0.67945 -0.3048)
			(end -0.67945 0.3048)
			(stroke
				(width 0.1)
				(type default)
			)
			(layer "B.Fab")
		)
		(fp_line
			(start -0.67945 0.3048)
			(end -0.120396 0.3048)
			(stroke
				(width 0.1)
				(type default)
			)
			(layer "B.Fab")
		)
		(fp_line
			(start -0.12065 -0.3048)
			(end -0.67945 -0.3048)
			(stroke
				(width 0.1)
				(type default)
			)
			(layer "B.Fab")
		)
		(fp_line
			(start -0.12065 -0.2794)
			(end -0.12065 -0.3048)
			(stroke
				(width 0.1)
				(type default)
			)
			(layer "B.Fab")
		)
		(fp_line
			(start -0.120396 0.2794)
			(end 0.12065 0.2794)
			(stroke
				(width 0.1)
				(type default)
			)
			(layer "B.Fab")
		)
		(fp_line
			(start -0.120396 0.3048)
			(end -0.120396 0.2794)
			(stroke
				(width 0.1)
				(type default)
			)
			(layer "B.Fab")
		)
		(fp_line
			(start 0.12065 -0.305054)
			(end 0.12065 -0.2794)
			(stroke
				(width 0.1)
				(type default)
			)
			(layer "B.Fab")
		)
		(fp_line
			(start 0.12065 -0.2794)
			(end -0.12065 -0.2794)
			(stroke
				(width 0.1)
				(type default)
			)
			(layer "B.Fab")
		)
		(fp_line
			(start 0.12065 0.2794)
			(end 0.12065 0.3048)
			(stroke
				(width 0.1)
				(type default)
			)
			(layer "B.Fab")
		)
		(fp_line
			(start 0.12065 0.3048)
			(end 0.67945 0.3048)
			(stroke
				(width 0.1)
				(type default)
			)
			(layer "B.Fab")
		)
		(fp_line
			(start 0.67945 -0.305054)
			(end 0.12065 -0.305054)
			(stroke
				(width 0.1)
				(type default)
			)
			(layer "B.Fab")
		)
		(fp_line
			(start 0.67945 0.3048)
			(end 0.67945 -0.305054)
			(stroke
				(width 0.1)
				(type default)
			)
			(layer "B.Fab")
		)
		(pad "1" smd circle
			(at 0.40005 0 180)
			(size 0 0)
			(layers "B.Cu" "B.Mask" "B.Paste")
			(net "SMB_BMC_MM14_R_SCL")
		)
		(pad "2" smd circle
			(at -0.40005 0 180)
			(size 0 0)
			(layers "B.Cu" "B.Mask" "B.Paste")
			(net "GND")
		)
	)
	(footprint ""
		(layer "B.Cu")
		(at 43.88866 -76.4286 180)
		(property "Reference" "R852"
			(at 0 0 0)
			(layer "B.SilkS")
			(hide yes)
			(effects
				(font
					(size 1.27 1.27)
				)
				(justify mirror)
			)
		)
		(property "Value" ""
			(at 0 0 0)
			(layer "B.Fab")
			(effects
				(font
					(size 1.27 1.27)
				)
				(justify mirror)
			)
		)
		(duplicate_pad_numbers_are_jumpers no)
		(fp_line
			(start 0.7874 0.4064)
			(end 0.7874 -0.4064)
			(stroke
				(width 0.1524)
				(type default)
			)
			(layer "B.SilkS")
		)
		(fp_line
			(start 0.7874 -0.4064)
			(end -0.7874 -0.4064)
			(stroke
				(width 0.1524)
				(type default)
			)
			(layer "B.SilkS")
		)
		(fp_line
			(start -0.7874 0.4064)
			(end 0.7874 0.4064)
			(stroke
				(width 0.1524)
				(type default)
			)
			(layer "B.SilkS")
		)
		(fp_line
			(start -0.7874 -0.4064)
			(end -0.7874 0.4064)
			(stroke
				(width 0.1524)
				(type default)
			)
			(layer "B.SilkS")
		)
		(fp_line
			(start 0.67945 0.3048)
			(end 0.67945 -0.305054)
			(stroke
				(width 0.1)
				(type default)
			)
			(layer "B.Fab")
		)
		(fp_line
			(start 0.67945 -0.305054)
			(end 0.12065 -0.305054)
			(stroke
				(width 0.1)
				(type default)
			)
			(layer "B.Fab")
		)
		(fp_line
			(start 0.12065 0.3048)
			(end 0.67945 0.3048)
			(stroke
				(width 0.1)
				(type default)
			)
			(layer "B.Fab")
		)
		(fp_line
			(start 0.12065 0.2794)
			(end 0.12065 0.3048)
			(stroke
				(width 0.1)
				(type default)
			)
			(layer "B.Fab")
		)
		(fp_line
			(start 0.12065 -0.2794)
			(end -0.12065 -0.2794)
			(stroke
				(width 0.1)
				(type default)
			)
			(layer "B.Fab")
		)
		(fp_line
			(start 0.12065 -0.305054)
			(end 0.12065 -0.2794)
			(stroke
				(width 0.1)
				(type default)
			)
			(layer "B.Fab")
		)
		(fp_line
			(start -0.120396 0.3048)
			(end -0.120396 0.2794)
			(stroke
				(width 0.1)
				(type default)
			)
			(layer "B.Fab")
		)
		(fp_line
			(start -0.120396 0.2794)
			(end 0.12065 0.2794)
			(stroke
				(width 0.1)
				(type default)
			)
			(layer "B.Fab")
		)
		(fp_line
			(start -0.12065 -0.2794)
			(end -0.12065 -0.3048)
			(stroke
				(width 0.1)
				(type default)
			)
			(layer "B.Fab")
		)
		(fp_line
			(start -0.12065 -0.3048)
			(end -0.67945 -0.3048)
			(stroke
				(width 0.1)
				(type default)
			)
			(layer "B.Fab")
		)
		(fp_line
			(start -0.67945 0.3048)
			(end -0.120396 0.3048)
			(stroke
				(width 0.1)
				(type default)
			)
			(layer "B.Fab")
		)
		(fp_line
			(start -0.67945 -0.3048)
			(end -0.67945 0.3048)
			(stroke
				(width 0.1)
				(type default)
			)
			(layer "B.Fab")
		)
		(pad "1" smd circle
			(at 0.40005 0)
			(size 0 0)
			(layers "B.Cu" "B.Mask" "B.Paste")
			(net "FM_BMC_MUX_CS_SPI_SEL_0")
		)
		(pad "2" smd circle
			(at -0.40005 0)
			(size 0 0)
			(layers "B.Cu" "B.Mask" "B.Paste")
			(net "FM_BMC_BIOS_MUX_CS_SPI_R_SEL_0")
		)
	)
)
